#ISCELL
  pure_quanta quanta_title_block_c *
  *
#CELL
  pure_quanta genoa_sp5 *
  page33_i4
#ISCELL
  pure_quanta_power universal_gnd *
  page33_i5
#ISCELL
  pure_quanta_power universal_gnd *
  page33_i6
